(kicad_pcb
	(version 20260206)
	(generator "pcbnew")
	(generator_version "10.0")
	(general
		(thickness 1.6)
		(legacy_teardrops no)
	)
	(paper "A4")
	(title_block
		(title "01162023_DA0F0TEBIF0_F0T_Expander_BD_F_brd_V02_OCP.brd")
		(comment 1 "Grand Teton / footprints 4063-4069 of 9728")
	)
	(layers
		(0 "F.Cu" signal "TOP")
		(4 "In1.Cu" signal "GND")
		(6 "In2.Cu" signal "VCC")
		(8 "In3.Cu" signal "VCC1")
		(10 "In4.Cu" signal "GND1")
		(12 "In5.Cu" signal "IN1")
		(14 "In6.Cu" signal "GND2")
		(16 "In7.Cu" signal "IN2")
		(18 "In8.Cu" signal "GND3")
		(20 "In9.Cu" signal "IN3")
		(22 "In10.Cu" signal "GND4")
		(24 "In11.Cu" signal "IN4")
		(26 "In12.Cu" signal "GND5")
		(28 "In13.Cu" signal "IN5")
		(30 "In14.Cu" signal "GND6")
		(32 "In15.Cu" signal "IN6")
		(34 "In16.Cu" signal "GND7")
		(2 "B.Cu" signal "BOTTOM")
		(9 "F.Adhes" user "F.Adhesive")
		(11 "B.Adhes" user "B.Adhesive")
		(13 "F.Paste" user "Package Geometry/Pastemask Top")
		(15 "B.Paste" user "Package Geometry/Pastemask Bottom")
		(5 "F.SilkS" user "Ref Des/Silkscreen Top")
		(7 "B.SilkS" user "Ref Des/Silkscreen Bottom")
		(1 "F.Mask" user "Board Geometry/Soldermask Top")
		(3 "B.Mask" user "Board Geometry/Soldermask Bottom")
		(17 "Dwgs.User" user "User.Drawings")
		(19 "Cmts.User" user "User.Comments")
		(21 "Eco1.User" user "User.Eco1")
		(23 "Eco2.User" user "User.Eco2")
		(25 "Edge.Cuts" user "Board Geometry/Outline")
		(27 "Margin" user)
		(31 "F.CrtYd" user "Package Geometry/Place Bound Top")
		(29 "B.CrtYd" user "Package Geometry/Place Bound Bottom")
		(35 "F.Fab" user "Ref Des/Assembly Top")
		(33 "B.Fab" user "Ref Des/Assembly Bottom")
	)
	(footprint ""
		(layer "F.Cu")
		(at 18.869914 -413.969708 90)
		(property "Reference" "R5593"
			(at 0 0 90)
			(layer "F.SilkS")
			(hide yes)
			(effects
				(font
					(size 1.27 1.27)
				)
			)
		)
		(property "Value" ""
			(at 0 0 90)
			(layer "F.Fab")
			(effects
				(font
					(size 1.27 1.27)
				)
			)
		)
		(duplicate_pad_numbers_are_jumpers no)
		(fp_line
			(start 0.7874 -0.4064)
			(end 0.7874 0.4064)
			(stroke
				(width 0.1524)
				(type default)
			)
			(layer "F.SilkS")
		)
		(fp_line
			(start -0.7874 -0.4064)
			(end 0.7874 -0.4064)
			(stroke
				(width 0.1524)
				(type default)
			)
			(layer "F.SilkS")
		)
		(fp_line
			(start 0.7874 0.4064)
			(end -0.7874 0.4064)
			(stroke
				(width 0.1524)
				(type default)
			)
			(layer "F.SilkS")
		)
		(fp_line
			(start -0.7874 0.4064)
			(end -0.7874 -0.4064)
			(stroke
				(width 0.1524)
				(type default)
			)
			(layer "F.SilkS")
		)
		(fp_line
			(start -0.12065 -0.305054)
			(end -0.12065 -0.2794)
			(stroke
				(width 0.1)
				(type default)
			)
			(layer "F.Fab")
		)
		(fp_line
			(start -0.67945 -0.305054)
			(end -0.12065 -0.305054)
			(stroke
				(width 0.1)
				(type default)
			)
			(layer "F.Fab")
		)
		(fp_line
			(start 0.67945 -0.3048)
			(end 0.67945 0.3048)
			(stroke
				(width 0.1)
				(type default)
			)
			(layer "F.Fab")
		)
		(fp_line
			(start 0.12065 -0.3048)
			(end 0.67945 -0.3048)
			(stroke
				(width 0.1)
				(type default)
			)
			(layer "F.Fab")
		)
		(fp_line
			(start 0.12065 -0.2794)
			(end 0.12065 -0.3048)
			(stroke
				(width 0.1)
				(type default)
			)
			(layer "F.Fab")
		)
		(fp_line
			(start -0.12065 -0.2794)
			(end 0.12065 -0.2794)
			(stroke
				(width 0.1)
				(type default)
			)
			(layer "F.Fab")
		)
		(fp_line
			(start 0.120396 0.2794)
			(end -0.12065 0.2794)
			(stroke
				(width 0.1)
				(type default)
			)
			(layer "F.Fab")
		)
		(fp_line
			(start -0.12065 0.2794)
			(end -0.12065 0.3048)
			(stroke
				(width 0.1)
				(type default)
			)
			(layer "F.Fab")
		)
		(fp_line
			(start 0.67945 0.3048)
			(end 0.120396 0.3048)
			(stroke
				(width 0.1)
				(type default)
			)
			(layer "F.Fab")
		)
		(fp_line
			(start 0.120396 0.3048)
			(end 0.120396 0.2794)
			(stroke
				(width 0.1)
				(type default)
			)
			(layer "F.Fab")
		)
		(fp_line
			(start -0.12065 0.3048)
			(end -0.67945 0.3048)
			(stroke
				(width 0.1)
				(type default)
			)
			(layer "F.Fab")
		)
		(fp_line
			(start -0.67945 0.3048)
			(end -0.67945 -0.305054)
			(stroke
				(width 0.1)
				(type default)
			)
			(layer "F.Fab")
		)
		(pad "1" smd circle
			(at -0.40005 0 90)
			(size 0 0)
			(layers "F.Cu" "F.Mask" "F.Paste")
			(net "LM75_0_A1")
		)
		(pad "2" smd circle
			(at 0.40005 0 90)
			(size 0 0)
			(layers "F.Cu" "F.Mask" "F.Paste")
			(net "GND")
		)
	)
	(footprint ""
		(layer "F.Cu")
		(at 289.954208 -48.21809)
		(property "Reference" "PD72"
			(at -3.391408 2.24536 0)
			(unlocked yes)
			(layer "F.SilkS")
			(effects
				(font
					(size 0.7874 0.5842)
					(thickness 0.1524)
				)
				(justify left)
			)
		)
		(property "Value" ""
			(at 0 0 0)
			(layer "F.Fab")
			(effects
				(font
					(size 1.27 1.27)
				)
			)
		)
		(duplicate_pad_numbers_are_jumpers no)
		(fp_line
			(start -3.400044 -1.459992)
			(end 4.107942 -1.459992)
			(stroke
				(width 0.1524)
				(type default)
			)
			(layer "F.SilkS")
		)
		(fp_line
			(start -3.400044 1.459992)
			(end -3.400044 -1.459992)
			(stroke
				(width 0.1524)
				(type default)
			)
			(layer "F.SilkS")
		)
		(fp_line
			(start 4.107942 -1.459992)
			(end 4.107942 1.459992)
			(stroke
				(width 0.1524)
				(type default)
			)
			(layer "F.SilkS")
		)
		(fp_line
			(start 4.107942 1.459992)
			(end -3.400044 1.459992)
			(stroke
				(width 0.1524)
				(type default)
			)
			(layer "F.SilkS")
		)
		(fp_poly
			(pts
				(xy 4.107942 -1.459992) (xy 4.107942 1.459992) (xy 3.308096 1.459992) (xy 3.308096 -1.459992)
			)
			(stroke
				(width 0)
				(type default)
			)
			(fill yes)
			(layer "F.SilkS")
		)
		(fp_line
			(start -2.29997 -1.459992)
			(end 2.29997 -1.459992)
			(stroke
				(width 0.1)
				(type default)
			)
			(layer "F.Fab")
		)
		(fp_line
			(start -2.29997 1.459992)
			(end -2.29997 -1.459992)
			(stroke
				(width 0.1)
				(type default)
			)
			(layer "F.Fab")
		)
		(fp_line
			(start 2.29997 -1.459992)
			(end 2.29997 1.459992)
			(stroke
				(width 0.1)
				(type default)
			)
			(layer "F.Fab")
		)
		(fp_line
			(start 2.29997 1.459992)
			(end -2.29997 1.459992)
			(stroke
				(width 0.1)
				(type default)
			)
			(layer "F.Fab")
		)
		(fp_text user "+"
			(at -4.7752 -0.12065 0)
			(unlocked yes)
			(layer "F.SilkS")
			(effects
				(font
					(size 1.905 1.4224)
					(thickness 0.1524)
				)
				(justify left)
			)
		)
		(fp_text user "-"
			(at 5.4102 0.29845 180)
			(unlocked yes)
			(layer "F.SilkS")
			(effects
				(font
					(size 1.905 1.4224)
					(thickness 0.1524)
				)
				(justify left)
			)
		)
		(fp_text user "+"
			(at -4.7752 -0.12065 0)
			(unlocked yes)
			(layer "F.Fab")
			(effects
				(font
					(size 1.905 1.4224)
					(thickness 0.1524)
				)
				(justify left)
			)
		)
		(fp_text user "-"
			(at 5.4102 0.29845 180)
			(unlocked yes)
			(layer "F.Fab")
			(effects
				(font
					(size 1.905 1.4224)
					(thickness 0.1524)
				)
				(justify left)
			)
		)
		(pad "A" smd rect
			(at -1.999996 0 90)
			(size 1.7018 2.5146)
			(layers "F.Cu" "F.Mask" "F.Paste")
			(net "GND")
		)
		(pad "C" smd rect
			(at 1.999996 0 90)
			(size 1.7018 2.5146)
			(layers "F.Cu" "F.Mask" "F.Paste")
			(net "P3V3_SSD10")
		)
	)
	(footprint ""
		(layer "F.Cu")
		(at 78.243684 -44.87291)
		(property "Reference" "R529"
			(at 0 0 0)
			(layer "F.SilkS")
			(hide yes)
			(effects
				(font
					(size 1.27 1.27)
				)
			)
		)
		(property "Value" ""
			(at 0 0 0)
			(layer "F.Fab")
			(effects
				(font
					(size 1.27 1.27)
				)
			)
		)
		(duplicate_pad_numbers_are_jumpers no)
		(fp_line
			(start -0.7874 -0.4064)
			(end 0.7874 -0.4064)
			(stroke
				(width 0.1524)
				(type default)
			)
			(layer "F.SilkS")
		)
		(fp_line
			(start -0.7874 0.4064)
			(end -0.7874 -0.4064)
			(stroke
				(width 0.1524)
				(type default)
			)
			(layer "F.SilkS")
		)
		(fp_line
			(start 0.7874 -0.4064)
			(end 0.7874 0.4064)
			(stroke
				(width 0.1524)
				(type default)
			)
			(layer "F.SilkS")
		)
		(fp_line
			(start 0.7874 0.4064)
			(end -0.7874 0.4064)
			(stroke
				(width 0.1524)
				(type default)
			)
			(layer "F.SilkS")
		)
		(fp_line
			(start -0.67945 -0.305054)
			(end -0.12065 -0.305054)
			(stroke
				(width 0.1)
				(type default)
			)
			(layer "F.Fab")
		)
		(fp_line
			(start -0.67945 0.3048)
			(end -0.67945 -0.305054)
			(stroke
				(width 0.1)
				(type default)
			)
			(layer "F.Fab")
		)
		(fp_line
			(start -0.12065 -0.305054)
			(end -0.12065 -0.2794)
			(stroke
				(width 0.1)
				(type default)
			)
			(layer "F.Fab")
		)
		(fp_line
			(start -0.12065 -0.2794)
			(end 0.12065 -0.2794)
			(stroke
				(width 0.1)
				(type default)
			)
			(layer "F.Fab")
		)
		(fp_line
			(start -0.12065 0.2794)
			(end -0.12065 0.3048)
			(stroke
				(width 0.1)
				(type default)
			)
			(layer "F.Fab")
		)
		(fp_line
			(start -0.12065 0.3048)
			(end -0.67945 0.3048)
			(stroke
				(width 0.1)
				(type default)
			)
			(layer "F.Fab")
		)
		(fp_line
			(start 0.120396 0.2794)
			(end -0.12065 0.2794)
			(stroke
				(width 0.1)
				(type default)
			)
			(layer "F.Fab")
		)
		(fp_line
			(start 0.120396 0.3048)
			(end 0.120396 0.2794)
			(stroke
				(width 0.1)
				(type default)
			)
			(layer "F.Fab")
		)
		(fp_line
			(start 0.12065 -0.3048)
			(end 0.67945 -0.3048)
			(stroke
				(width 0.1)
				(type default)
			)
			(layer "F.Fab")
		)
		(fp_line
			(start 0.12065 -0.2794)
			(end 0.12065 -0.3048)
			(stroke
				(width 0.1)
				(type default)
			)
			(layer "F.Fab")
		)
		(fp_line
			(start 0.67945 -0.3048)
			(end 0.67945 0.3048)
			(stroke
				(width 0.1)
				(type default)
			)
			(layer "F.Fab")
		)
		(fp_line
			(start 0.67945 0.3048)
			(end 0.120396 0.3048)
			(stroke
				(width 0.1)
				(type default)
			)
			(layer "F.Fab")
		)
		(pad "1" smd circle
			(at -0.40005 0)
			(size 0 0)
			(layers "F.Cu" "F.Mask" "F.Paste")
			(net "SSD2_ADC_A0")
		)
		(pad "2" smd circle
			(at 0.40005 0)
			(size 0 0)
			(layers "F.Cu" "F.Mask" "F.Paste")
			(net "P3V3_AUX")
		)
	)
	(footprint ""
		(layer "F.Cu")
		(at 393.771628 -25.342342 -90)
		(property "Reference" "R448"
			(at 0 0 270)
			(layer "F.SilkS")
			(hide yes)
			(effects
				(font
					(size 1.27 1.27)
				)
			)
		)
		(property "Value" ""
			(at 0 0 270)
			(layer "F.Fab")
			(effects
				(font
					(size 1.27 1.27)
				)
			)
		)
		(duplicate_pad_numbers_are_jumpers no)
		(fp_line
			(start -0.7874 0.4064)
			(end -0.7874 -0.4064)
			(stroke
				(width 0.1524)
				(type default)
			)
			(layer "F.SilkS")
		)
		(fp_line
			(start 0.7874 0.4064)
			(end -0.7874 0.4064)
			(stroke
				(width 0.1524)
				(type default)
			)
			(layer "F.SilkS")
		)
		(fp_line
			(start -0.7874 -0.4064)
			(end 0.7874 -0.4064)
			(stroke
				(width 0.1524)
				(type default)
			)
			(layer "F.SilkS")
		)
		(fp_line
			(start 0.7874 -0.4064)
			(end 0.7874 0.4064)
			(stroke
				(width 0.1524)
				(type default)
			)
			(layer "F.SilkS")
		)
		(fp_line
			(start -0.67945 0.3048)
			(end -0.67945 -0.305054)
			(stroke
				(width 0.1)
				(type default)
			)
			(layer "F.Fab")
		)
		(fp_line
			(start -0.12065 0.3048)
			(end -0.67945 0.3048)
			(stroke
				(width 0.1)
				(type default)
			)
			(layer "F.Fab")
		)
		(fp_line
			(start 0.120396 0.3048)
			(end 0.120396 0.2794)
			(stroke
				(width 0.1)
				(type default)
			)
			(layer "F.Fab")
		)
		(fp_line
			(start 0.67945 0.3048)
			(end 0.120396 0.3048)
			(stroke
				(width 0.1)
				(type default)
			)
			(layer "F.Fab")
		)
		(fp_line
			(start -0.12065 0.2794)
			(end -0.12065 0.3048)
			(stroke
				(width 0.1)
				(type default)
			)
			(layer "F.Fab")
		)
		(fp_line
			(start 0.120396 0.2794)
			(end -0.12065 0.2794)
			(stroke
				(width 0.1)
				(type default)
			)
			(layer "F.Fab")
		)
		(fp_line
			(start -0.12065 -0.2794)
			(end 0.12065 -0.2794)
			(stroke
				(width 0.1)
				(type default)
			)
			(layer "F.Fab")
		)
		(fp_line
			(start 0.12065 -0.2794)
			(end 0.12065 -0.3048)
			(stroke
				(width 0.1)
				(type default)
			)
			(layer "F.Fab")
		)
		(fp_line
			(start 0.12065 -0.3048)
			(end 0.67945 -0.3048)
			(stroke
				(width 0.1)
				(type default)
			)
			(layer "F.Fab")
		)
		(fp_line
			(start 0.67945 -0.3048)
			(end 0.67945 0.3048)
			(stroke
				(width 0.1)
				(type default)
			)
			(layer "F.Fab")
		)
		(fp_line
			(start -0.67945 -0.305054)
			(end -0.12065 -0.305054)
			(stroke
				(width 0.1)
				(type default)
			)
			(layer "F.Fab")
		)
		(fp_line
			(start -0.12065 -0.305054)
			(end -0.12065 -0.2794)
			(stroke
				(width 0.1)
				(type default)
			)
			(layer "F.Fab")
		)
		(pad "1" smd circle
			(at -0.40005 0 270)
			(size 0 0)
			(layers "F.Cu" "F.Mask" "F.Paste")
			(net "P3V3_SSD13")
		)
		(pad "2" smd circle
			(at 0.40005 0 270)
			(size 0 0)
			(layers "F.Cu" "F.Mask" "F.Paste")
			(net "DUALPORT_N_SSD13")
		)
	)
	(footprint ""
		(layer "F.Cu")
		(at 107.581954 -79.822294 90)
		(property "Reference" "R1138"
			(at 0 0 90)
			(layer "F.SilkS")
			(hide yes)
			(effects
				(font
					(size 1.27 1.27)
				)
			)
		)
		(property "Value" ""
			(at 0 0 90)
			(layer "F.Fab")
			(effects
				(font
					(size 1.27 1.27)
				)
			)
		)
		(duplicate_pad_numbers_are_jumpers no)
		(fp_line
			(start -0.7874 -0.4064)
			(end 0.7874 -0.4064)
			(stroke
				(width 0.1524)
				(type default)
			)
			(layer "F.SilkS")
		)
		(fp_line
			(start -0.12065 -0.305054)
			(end -0.12065 -0.2794)
			(stroke
				(width 0.1)
				(type default)
			)
			(layer "F.Fab")
		)
		(fp_line
			(start -0.67945 -0.305054)
			(end -0.12065 -0.305054)
			(stroke
				(width 0.1)
				(type default)
			)
			(layer "F.Fab")
		)
		(fp_line
			(start 0.67945 -0.3048)
			(end 0.67945 0.3048)
			(stroke
				(width 0.1)
				(type default)
			)
			(layer "F.Fab")
		)
		(fp_line
			(start 0.12065 -0.3048)
			(end 0.67945 -0.3048)
			(stroke
				(width 0.1)
				(type default)
			)
			(layer "F.Fab")
		)
		(fp_line
			(start 0.12065 -0.2794)
			(end 0.12065 -0.3048)
			(stroke
				(width 0.1)
				(type default)
			)
			(layer "F.Fab")
		)
		(fp_line
			(start -0.12065 -0.2794)
			(end 0.12065 -0.2794)
			(stroke
				(width 0.1)
				(type default)
			)
			(layer "F.Fab")
		)
		(fp_line
			(start 0.120396 0.2794)
			(end -0.12065 0.2794)
			(stroke
				(width 0.1)
				(type default)
			)
			(layer "F.Fab")
		)
		(fp_line
			(start -0.12065 0.2794)
			(end -0.12065 0.3048)
			(stroke
				(width 0.1)
				(type default)
			)
			(layer "F.Fab")
		)
		(fp_line
			(start 0.67945 0.3048)
			(end 0.120396 0.3048)
			(stroke
				(width 0.1)
				(type default)
			)
			(layer "F.Fab")
		)
		(fp_line
			(start 0.120396 0.3048)
			(end 0.120396 0.2794)
			(stroke
				(width 0.1)
				(type default)
			)
			(layer "F.Fab")
		)
		(fp_line
			(start -0.12065 0.3048)
			(end -0.67945 0.3048)
			(stroke
				(width 0.1)
				(type default)
			)
			(layer "F.Fab")
		)
		(fp_line
			(start -0.67945 0.3048)
			(end -0.67945 -0.305054)
			(stroke
				(width 0.1)
				(type default)
			)
			(layer "F.Fab")
		)
		(pad "1" smd circle
			(at -0.40005 0 90)
			(size 0 0)
			(layers "F.Cu" "F.Mask" "F.Paste")
			(net "CLK_100M_DB800ZL_SSD1_R_DP")
		)
		(pad "2" smd circle
			(at 0.40005 0 90)
			(size 0 0)
			(layers "F.Cu" "F.Mask" "F.Paste")
			(net "CLK_100M_DB800ZL_SSD1_DP")
		)
	)
	(footprint ""
		(layer "F.Cu")
		(at 22.82063 -70.307454 90)
		(property "Reference" "PC639"
			(at 0 0 90)
			(layer "F.SilkS")
			(hide yes)
			(effects
				(font
					(size 1.27 1.27)
				)
			)
		)
		(property "Value" ""
			(at 0 0 90)
			(layer "F.Fab")
			(effects
				(font
					(size 1.27 1.27)
				)
			)
		)
		(duplicate_pad_numbers_are_jumpers no)
		(fp_line
			(start 0.7874 -0.4064)
			(end 0.7874 0.4064)
			(stroke
				(width 0.1524)
				(type default)
			)
			(layer "F.SilkS")
		)
		(fp_line
			(start -0.7874 -0.4064)
			(end 0.7874 -0.4064)
			(stroke
				(width 0.1524)
				(type default)
			)
			(layer "F.SilkS")
		)
		(fp_line
			(start 0.7874 0.4064)
			(end -0.7874 0.4064)
			(stroke
				(width 0.1524)
				(type default)
			)
			(layer "F.SilkS")
		)
		(fp_line
			(start -0.7874 0.4064)
			(end -0.7874 -0.4064)
			(stroke
				(width 0.1524)
				(type default)
			)
			(layer "F.SilkS")
		)
		(fp_line
			(start -0.12065 -0.305054)
			(end -0.12065 -0.2794)
			(stroke
				(width 0.1)
				(type default)
			)
			(layer "F.Fab")
		)
		(fp_line
			(start -0.67945 -0.305054)
			(end -0.12065 -0.305054)
			(stroke
				(width 0.1)
				(type default)
			)
			(layer "F.Fab")
		)
		(fp_line
			(start 0.67945 -0.3048)
			(end 0.67945 0.3048)
			(stroke
				(width 0.1)
				(type default)
			)
			(layer "F.Fab")
		)
		(fp_line
			(start 0.12065 -0.3048)
			(end 0.67945 -0.3048)
			(stroke
				(width 0.1)
				(type default)
			)
			(layer "F.Fab")
		)
		(fp_line
			(start 0.12065 -0.2794)
			(end 0.12065 -0.3048)
			(stroke
				(width 0.1)
				(type default)
			)
			(layer "F.Fab")
		)
		(fp_line
			(start -0.12065 -0.2794)
			(end 0.12065 -0.2794)
			(stroke
				(width 0.1)
				(type default)
			)
			(layer "F.Fab")
		)
		(fp_line
			(start 0.120396 0.2794)
			(end -0.12065 0.2794)
			(stroke
				(width 0.1)
				(type default)
			)
			(layer "F.Fab")
		)
		(fp_line
			(start -0.12065 0.2794)
			(end -0.12065 0.3048)
			(stroke
				(width 0.1)
				(type default)
			)
			(layer "F.Fab")
		)
		(fp_line
			(start 0.67945 0.3048)
			(end 0.120396 0.3048)
			(stroke
				(width 0.1)
				(type default)
			)
			(layer "F.Fab")
		)
		(fp_line
			(start 0.120396 0.3048)
			(end 0.120396 0.2794)
			(stroke
				(width 0.1)
				(type default)
			)
			(layer "F.Fab")
		)
		(fp_line
			(start -0.12065 0.3048)
			(end -0.67945 0.3048)
			(stroke
				(width 0.1)
				(type default)
			)
			(layer "F.Fab")
		)
		(fp_line
			(start -0.67945 0.3048)
			(end -0.67945 -0.305054)
			(stroke
				(width 0.1)
				(type default)
			)
			(layer "F.Fab")
		)
		(pad "1" smd circle
			(at -0.40005 0 90)
			(size 0 0)
			(layers "F.Cu" "F.Mask" "F.Paste")
			(net "P12V_AUX")
		)
		(pad "2" smd circle
			(at 0.40005 0 90)
			(size 0 0)
			(layers "F.Cu" "F.Mask" "F.Paste")
			(net "GND")
		)
	)
	(footprint ""
		(layer "F.Cu")
		(at 30.153356 -284.990032)
		(property "Reference" "L95"
			(at 0 0 0)
			(layer "F.SilkS")
			(hide yes)
			(effects
				(font
					(size 1.27 1.27)
				)
			)
		)
		(property "Value" ""
			(at 0 0 0)
			(layer "F.Fab")
			(effects
				(font
					(size 1.27 1.27)
				)
			)
		)
		(duplicate_pad_numbers_are_jumpers no)
		(fp_line
			(start -1.63576 -0.8128)
			(end -1.63576 0.8128)
			(stroke
				(width 0.1524)
				(type default)
			)
			(layer "F.SilkS")
		)
		(fp_line
			(start -1.63576 -0.8128)
			(end 1.63576 -0.8128)
			(stroke
				(width 0.1524)
				(type default)
			)
			(layer "F.SilkS")
		)
		(fp_line
			(start 1.63576 -0.8128)
			(end 1.63576 0.8128)
			(stroke
				(width 0.1524)
				(type default)
			)
			(layer "F.SilkS")
		)
		(fp_line
			(start 1.63576 0.8128)
			(end -1.63576 0.8128)
			(stroke
				(width 0.1524)
				(type default)
			)
			(layer "F.SilkS")
		)
		(fp_line
			(start -1.56083 -0.738632)
			(end -1.56083 0.7366)
			(stroke
				(width 0.1)
				(type default)
			)
			(layer "F.Fab")
		)
		(fp_line
			(start -1.56083 0.7366)
			(end -1.524 0.7366)
			(stroke
				(width 0.1)
				(type default)
			)
			(layer "F.Fab")
		)
		(fp_line
			(start -1.524 0.7366)
			(end 1.524 0.7366)
			(stroke
				(width 0.1)
				(type default)
			)
			(layer "F.Fab")
		)
		(fp_line
			(start 1.524 0.7366)
			(end 1.560576 0.7366)
			(stroke
				(width 0.1)
				(type default)
			)
			(layer "F.Fab")
		)
		(fp_line
			(start 1.560576 -0.738632)
			(end -1.56083 -0.738632)
			(stroke
				(width 0.1)
				(type default)
			)
			(layer "F.Fab")
		)
		(fp_line
			(start 1.560576 0.7366)
			(end 1.560576 -0.738632)
			(stroke
				(width 0.1)
				(type default)
			)
			(layer "F.Fab")
		)
		(pad "1" smd rect
			(at -0.94996 0 180)
			(size 1.1176 1.3716)
			(layers "F.Cu" "F.Mask" "F.Paste")
			(net "P1V8_PLL0_PEX0")
		)
		(pad "2" smd rect
			(at 0.94996 0 180)
			(size 1.1176 1.3716)
			(layers "F.Cu" "F.Mask" "F.Paste")
			(net "PCEPLL7_VDDA18_PEX0")
		)
	)
)
